(kicad_pcb
	(version 20241229)
	(generator "pcbnew")
	(generator_version "9.0")
	(general
		(thickness 1.61)
		(legacy_teardrops no)
	)
	(paper "A3")
	(title_block
		(title "RDIMM DDR5 Tester")
		(date "2026-05-21")
		(rev "2.2.0")
		(company "Antmicro")
		(comment 9 "footprints 731-734 of 796")
	)
	(layers
		(0 "F.Cu" signal)
		(4 "In1.Cu" power)
		(6 "In2.Cu" mixed)
		(8 "In3.Cu" power)
		(10 "In4.Cu" mixed)
		(12 "In5.Cu" power)
		(14 "In6.Cu" mixed)
		(16 "In7.Cu" power)
		(18 "In8.Cu" power)
		(20 "In9.Cu" mixed)
		(22 "In10.Cu" power)
		(2 "B.Cu" signal)
		(9 "F.Adhes" user "F.Adhesive")
		(11 "B.Adhes" user "B.Adhesive")
		(13 "F.Paste" user)
		(15 "B.Paste" user)
		(5 "F.SilkS" user "F.Silkscreen")
		(7 "B.SilkS" user "B.Silkscreen")
		(1 "F.Mask" user)
		(3 "B.Mask" user)
		(17 "Dwgs.User" user "User.Drawings")
		(19 "Cmts.User" user "User.Comments")
		(21 "Eco1.User" user "User.Eco1")
		(23 "Eco2.User" user "User.Eco2")
		(25 "Edge.Cuts" user)
		(27 "Margin" user)
		(31 "F.CrtYd" user "F.Courtyard")
		(29 "B.CrtYd" user "B.Courtyard")
		(35 "F.Fab" user)
		(33 "B.Fab" user)
	)
	(footprint "antmicro-footprints:SC70-3"
		(layer "B.Cu")
		(at 114.755 107.55 180)
		(property "Reference" "Q5"
			(at -3.355 -0.334 0)
			(layer "B.SilkS")
			(effects
				(font
					(size 0.7 0.7)
					(thickness 0.15)
				)
				(justify left bottom mirror)
			)
		)
		(property "Value" "BSS138PW"
			(at 0 -2.3 0)
			(layer "B.Fab")
			(effects
				(font
					(size 0.7 0.7)
					(thickness 0.15)
				)
				(justify left bottom mirror)
			)
		)
		(property "Datasheet" "https://assets.nexperia.com/documents/data-sheet/BSS138PW.pdf"
			(at 0 0 180)
			(layer "F.Fab")
			(hide yes)
			(effects
				(font
					(size 1.27 1.27)
					(thickness 0.15)
				)
			)
		)
		(property "MPN" "BSS138PW"
			(at 0 0 180)
			(unlocked yes)
			(layer "B.Fab")
			(hide yes)
			(effects
				(font
					(size 1 1)
					(thickness 0.15)
				)
				(justify mirror)
			)
		)
		(property "Manufacturer" "Nexperia"
			(at 0 0 180)
			(unlocked yes)
			(layer "B.Fab")
			(hide yes)
			(effects
				(font
					(size 1 1)
					(thickness 0.15)
				)
				(justify mirror)
			)
		)
		(property "Author" "Antmicro"
			(at 0 0 180)
			(unlocked yes)
			(layer "B.Fab")
			(hide yes)
			(effects
				(font
					(size 1 1)
					(thickness 0.15)
				)
				(justify mirror)
			)
		)
		(property "License" "Apache-2.0"
			(at 0 0 180)
			(unlocked yes)
			(layer "B.Fab")
			(hide yes)
			(effects
				(font
					(size 1 1)
					(thickness 0.15)
				)
				(justify mirror)
			)
		)
		(sheetname "/FPGA banks HD/")
		(sheetfile "fpga-hd-banks.kicad_sch")
		(attr smd)
		(fp_line
			(start 0.627 0.6)
			(end 0.627 0.999)
			(stroke
				(width 0.15)
				(type solid)
			)
			(layer "B.SilkS")
		)
		(fp_line
			(start 0.627 -0.6)
			(end 0.627 -1.001)
			(stroke
				(width 0.15)
				(type solid)
			)
			(layer "B.SilkS")
		)
		(fp_line
			(start -0.3 1)
			(end 0.627 0.999)
			(stroke
				(width 0.15)
				(type solid)
			)
			(layer "B.SilkS")
		)
		(fp_line
			(start -0.3 -1)
			(end 0.627 -1.001)
			(stroke
				(width 0.15)
				(type solid)
			)
			(layer "B.SilkS")
		)
		(fp_line
			(start 1.4 0.4)
			(end 1.4 -0.4)
			(stroke
				(width 0.05)
				(type solid)
			)
			(layer "B.CrtYd")
		)
		(fp_line
			(start 1.4 -0.4)
			(end 0.9 -0.4)
			(stroke
				(width 0.05)
				(type solid)
			)
			(layer "B.CrtYd")
		)
		(fp_line
			(start 0.9 1.3)
			(end 0.9 0.4)
			(stroke
				(width 0.05)
				(type solid)
			)
			(layer "B.CrtYd")
		)
		(fp_line
			(start 0.9 0.4)
			(end 1.4 0.4)
			(stroke
				(width 0.05)
				(type solid)
			)
			(layer "B.CrtYd")
		)
		(fp_line
			(start 0.9 -0.4)
			(end 0.9 -1.3)
			(stroke
				(width 0.05)
				(type solid)
			)
			(layer "B.CrtYd")
		)
		(fp_line
			(start 0.9 -1.3)
			(end -0.9 -1.3)
			(stroke
				(width 0.05)
				(type solid)
			)
			(layer "B.CrtYd")
		)
		(fp_line
			(start -0.9 1.3)
			(end 0.9 1.3)
			(stroke
				(width 0.05)
				(type solid)
			)
			(layer "B.CrtYd")
		)
		(fp_line
			(start -0.9 1.3)
			(end -0.9 1)
			(stroke
				(width 0.05)
				(type solid)
			)
			(layer "B.CrtYd")
		)
		(fp_line
			(start -0.9 1)
			(end -1.4 1)
			(stroke
				(width 0.05)
				(type solid)
			)
			(layer "B.CrtYd")
		)
		(fp_line
			(start -0.9 -1)
			(end -1.4 -1)
			(stroke
				(width 0.05)
				(type solid)
			)
			(layer "B.CrtYd")
		)
		(fp_line
			(start -0.9 -1.3)
			(end -0.9 -1)
			(stroke
				(width 0.05)
				(type solid)
			)
			(layer "B.CrtYd")
		)
		(fp_line
			(start -1.4 -1)
			(end -1.4 1)
			(stroke
				(width 0.05)
				(type solid)
			)
			(layer "B.CrtYd")
		)
		(fp_rect
			(start -0.623 0.999)
			(end 0.627 -1.001)
			(stroke
				(width 0.15)
				(type solid)
			)
			(fill no)
			(layer "B.Fab")
		)
		(fp_text user "License: Apache-2.0"
			(at -1.45 -6.782 0)
			(layer "B.Fab")
			(effects
				(font
					(size 0.7 0.7)
					(thickness 0.15)
				)
				(justify left bottom mirror)
			)
		)
		(fp_text user "Author: Antmicro"
			(at -1.45 -5.782 0)
			(layer "B.Fab")
			(effects
				(font
					(size 0.7 0.7)
					(thickness 0.15)
				)
				(justify left bottom mirror)
			)
		)
		(fp_text user "${REFERENCE}"
			(at -1.45 -4.783 0)
			(layer "B.Fab")
			(effects
				(font
					(size 0.7 0.7)
					(thickness 0.15)
				)
				(justify left bottom mirror)
			)
		)
		(pad "1" smd rect
			(at -1.051 0.65 90)
			(size 0.6 0.6)
			(layers "B.Cu" "B.Mask" "B.Paste")
			(net 700 "/FPGA banks HD/USR_LED4")
			(pinfunction "G")
			(pintype "passive")
		)
		(pad "2" smd rect
			(at -1.051 -0.65 90)
			(size 0.6 0.6)
			(layers "B.Cu" "B.Mask" "B.Paste")
			(net 1 "GND")
			(pinfunction "S")
			(pintype "passive")
		)
		(pad "3" smd rect
			(at 1.05 0 90)
			(size 0.6 0.6)
			(layers "B.Cu" "B.Mask" "B.Paste")
			(net 273 "Net-(Q5-D)")
			(pinfunction "D")
			(pintype "passive")
		)
	)
	(footprint "antmicro-footprints:C_0402_1005Metric_EIA"
		(layer "B.Cu")
		(at 184.500001 156 180)
		(descr "Capacitor SMD 0402 (1005 Metric), square (rectangular) end terminal, IPC_7351 nominal, (Body size source: IPC-SM-782 page 76, https://www.pcb-3d.com/wordpress/wp-content/uploads/ipc-sm-782a_amendment_1_and_2.pdf)")
		(tags "capacitor 0402")
		(property "Reference" "C46"
			(at 30.075001 10.5 0)
			(layer "B.SilkS")
			(effects
				(font
					(size 0.7 0.7)
					(thickness 0.15)
				)
				(justify left bottom mirror)
			)
		)
		(property "Value" "C_1u_25V_0402"
			(at 0 -1.169 0)
			(layer "B.Fab")
			(effects
				(font
					(size 0.7 0.7)
					(thickness 0.15)
				)
				(justify left bottom mirror)
			)
		)
		(property "Datasheet" "https://www.murata.com/products/productdetail?partno=GRM155R61E105KE11%23"
			(at 0 0 180)
			(layer "F.Fab")
			(hide yes)
			(effects
				(font
					(size 1.27 1.27)
					(thickness 0.15)
				)
			)
		)
		(property "MPN" "GRM155R61E105KE11J"
			(at 0 0 180)
			(unlocked yes)
			(layer "B.Fab")
			(hide yes)
			(effects
				(font
					(size 1 1)
					(thickness 0.15)
				)
				(justify mirror)
			)
		)
		(property "Manufacturer" "Murata"
			(at 0 0 180)
			(unlocked yes)
			(layer "B.Fab")
			(hide yes)
			(effects
				(font
					(size 1 1)
					(thickness 0.15)
				)
				(justify mirror)
			)
		)
		(property "License" "Apache-2.0"
			(at 0 0 180)
			(unlocked yes)
			(layer "B.Fab")
			(hide yes)
			(effects
				(font
					(size 1 1)
					(thickness 0.15)
				)
				(justify mirror)
			)
		)
		(property "Author" "Antmicro"
			(at 0 0 180)
			(unlocked yes)
			(layer "B.Fab")
			(hide yes)
			(effects
				(font
					(size 1 1)
					(thickness 0.15)
				)
				(justify mirror)
			)
		)
		(property "Val" "1u"
			(at 0 0 180)
			(unlocked yes)
			(layer "B.Fab")
			(hide yes)
			(effects
				(font
					(size 1 1)
					(thickness 0.15)
				)
				(justify mirror)
			)
		)
		(property "Voltage" "25V"
			(at 0 0 180)
			(unlocked yes)
			(layer "B.Fab")
			(hide yes)
			(effects
				(font
					(size 1 1)
					(thickness 0.15)
				)
				(justify mirror)
			)
		)
		(property "Dielectric" "X5R"
			(at 0 0 180)
			(unlocked yes)
			(layer "B.Fab")
			(hide yes)
			(effects
				(font
					(size 1 1)
					(thickness 0.15)
				)
				(justify mirror)
			)
		)
		(sheetname "/FPGA power/")
		(sheetfile "fpga-power.kicad_sch")
		(attr smd)
		(fp_rect
			(start -0.95 0.45)
			(end 0.95 -0.45)
			(stroke
				(width 0.05)
				(type default)
			)
			(fill no)
			(layer "B.CrtYd")
		)
		(fp_line
			(start 0.498 0.25)
			(end 0.498 -0.248)
			(stroke
				(width 0.15)
				(type solid)
			)
			(layer "B.Fab")
		)
		(fp_line
			(start 0.498 -0.248)
			(end -0.5 -0.248)
			(stroke
				(width 0.15)
				(type solid)
			)
			(layer "B.Fab")
		)
		(fp_line
			(start -0.5 0.25)
			(end 0.498 0.25)
			(stroke
				(width 0.15)
				(type solid)
			)
			(layer "B.Fab")
		)
		(fp_line
			(start -0.5 -0.248)
			(end -0.5 0.25)
			(stroke
				(width 0.15)
				(type solid)
			)
			(layer "B.Fab")
		)
		(fp_text user "License: Apache-2.0"
			(at -0.9656 -4.369 0)
			(layer "B.Fab")
			(effects
				(font
					(size 0.7 0.7)
					(thickness 0.15)
				)
				(justify left bottom mirror)
			)
		)
		(fp_text user "${REFERENCE}"
			(at -0.9656 -3.169 0)
			(layer "B.Fab")
			(effects
				(font
					(size 0.7 0.7)
					(thickness 0.15)
				)
				(justify left bottom mirror)
			)
		)
		(fp_text user "Author: Antmicro"
			(at -0.9656 -5.569 0)
			(layer "B.Fab")
			(effects
				(font
					(size 0.7 0.7)
					(thickness 0.15)
				)
				(justify left bottom mirror)
			)
		)
		(pad "1" smd roundrect
			(at -0.5 0 90)
			(size 0.6 0.6)
			(layers "B.Cu" "B.Mask" "B.Paste")
			(roundrect_rratio 0.25)
			(net 1 "GND")
			(pintype "passive")
		)
		(pad "2" smd roundrect
			(at 0.498 0 180)
			(size 0.6 0.6)
			(layers "B.Cu" "B.Mask" "B.Paste")
			(roundrect_rratio 0.25)
			(net 553 "+0V85")
			(pintype "passive")
		)
	)
	(footprint "antmicro-footprints:R_0402_1005Metric"
		(layer "B.Cu")
		(at 222.875 179.785 90)
		(descr "Resistor SMD 0402")
		(tags "resistor SMD 0402")
		(property "Reference" "R201"
			(at -2.165 1.75 90)
			(layer "B.SilkS")
			(effects
				(font
					(size 0.7 0.7)
					(thickness 0.15)
				)
				(justify right bottom mirror)
			)
		)
		(property "Value" "R_3k4_0402"
			(at -1.011843 -1.772047 90)
			(layer "B.Fab")
			(effects
				(font
					(size 0.7 0.7)
					(thickness 0.15)
				)
				(justify right bottom mirror)
			)
		)
		(property "Datasheet" "https://www.yageo.com/upload/media/product/app/datasheet/rchip/pyu-rt_1-to-0.01_rohs_l.pdf"
			(at 0 0 90)
			(layer "F.Fab")
			(hide yes)
			(effects
				(font
					(size 1.27 1.27)
					(thickness 0.15)
				)
			)
		)
		(property "MPN" "RT0402BRD073K4L"
			(at 0 0 90)
			(unlocked yes)
			(layer "B.Fab")
			(hide yes)
			(effects
				(font
					(size 1 1)
					(thickness 0.15)
				)
				(justify mirror)
			)
		)
		(property "Manufacturer" "YAGEO"
			(at 0 0 90)
			(unlocked yes)
			(layer "B.Fab")
			(hide yes)
			(effects
				(font
					(size 1 1)
					(thickness 0.15)
				)
				(justify mirror)
			)
		)
		(property "License" "Apache-2.0"
			(at 0 0 90)
			(unlocked yes)
			(layer "B.Fab")
			(hide yes)
			(effects
				(font
					(size 1 1)
					(thickness 0.15)
				)
				(justify mirror)
			)
		)
		(property "Author" "Antmicro"
			(at 0 0 90)
			(unlocked yes)
			(layer "B.Fab")
			(hide yes)
			(effects
				(font
					(size 1 1)
					(thickness 0.15)
				)
				(justify mirror)
			)
		)
		(property "Val" "3k4"
			(at 0 0 90)
			(unlocked yes)
			(layer "B.Fab")
			(hide yes)
			(effects
				(font
					(size 1 1)
					(thickness 0.15)
				)
				(justify mirror)
			)
		)
		(property "Tolerance" "0.1%"
			(at 0 0 90)
			(unlocked yes)
			(layer "B.Fab")
			(hide yes)
			(effects
				(font
					(size 1 1)
					(thickness 0.15)
				)
				(justify mirror)
			)
		)
		(sheetname "/Supply/DC-DC VCCINT/")
		(sheetfile "dc-dc-vccint.kicad_sch")
		(attr smd)
		(fp_rect
			(start -0.925 0.47)
			(end 0.925 -0.47)
			(stroke
				(width 0.05)
				(type default)
			)
			(fill no)
			(layer "B.CrtYd")
		)
		(fp_rect
			(start -0.5 0.25)
			(end 0.5 -0.25)
			(stroke
				(width 0.15)
				(type solid)
			)
			(fill no)
			(layer "B.Fab")
		)
		(fp_text user "License: Apache-2.0"
			(at -0.95 -5.169 270)
			(layer "B.Fab")
			(effects
				(font
					(size 0.7 0.7)
					(thickness 0.15)
				)
				(justify left bottom mirror)
			)
		)
		(fp_text user "Author: Antmicro"
			(at -0.95 -4.169 270)
			(layer "B.Fab")
			(effects
				(font
					(size 0.7 0.7)
					(thickness 0.15)
				)
				(justify left bottom mirror)
			)
		)
		(fp_text user "${REFERENCE}"
			(at -0.95 -3.168 270)
			(layer "B.Fab")
			(effects
				(font
					(size 0.7 0.7)
					(thickness 0.15)
				)
				(justify left bottom mirror)
			)
		)
		(pad "1" smd roundrect
			(at -0.48 0 90)
			(size 0.59 0.64)
			(layers "B.Cu" "B.Mask" "B.Paste")
			(roundrect_rratio 0.25)
			(net 226 "/Supply/DC-DC VCCINT/V_{0SNS+}")
			(pintype "passive")
		)
		(pad "2" smd roundrect
			(at 0.48 0 90)
			(size 0.59 0.64)
			(layers "B.Cu" "B.Mask" "B.Paste")
			(roundrect_rratio 0.25)
			(net 756 "Net-(C264-Pad2)")
			(pintype "passive")
		)
	)
	(footprint "antmicro-footprints:R_0402_1005Metric_EIA"
		(layer "B.Cu")
		(at 180 149.5 -90)
		(descr "Resistor SMD 0402 (1005 Metric), square (rectangular) end terminal, IPC_7351 nominal, (Body size source: IPC-SM-782 page 76, https://www.pcb-3d.com/wordpress/wp-content/uploads/ipc-sm-782a_amendment_1_and_2.pdf)")
		(tags "resistor 0402")
		(property "Reference" "R182"
			(at -1.425 0.575 90)
			(layer "B.SilkS")
			(effects
				(font
					(size 0.7 0.7)
					(thickness 0.15)
				)
				(justify left bottom mirror)
			)
		)
		(property "Value" "R_240R_0402"
			(at 0 -1.169 90)
			(layer "B.Fab")
			(effects
				(font
					(size 0.7 0.7)
					(thickness 0.15)
				)
				(justify left bottom mirror)
			)
		)
		(property "Datasheet" "https://www.bourns.com/docs/product-datasheets/cr.pdf"
			(at 0 0 270)
			(layer "F.Fab")
			(hide yes)
			(effects
				(font
					(size 1.27 1.27)
					(thickness 0.15)
				)
			)
		)
		(property "MPN" "CR0402-FX-2400GLF"
			(at 0 0 270)
			(unlocked yes)
			(layer "B.Fab")
			(hide yes)
			(effects
				(font
					(size 1 1)
					(thickness 0.15)
				)
				(justify mirror)
			)
		)
		(property "Manufacturer" "Bourns"
			(at 0 0 270)
			(unlocked yes)
			(layer "B.Fab")
			(hide yes)
			(effects
				(font
					(size 1 1)
					(thickness 0.15)
				)
				(justify mirror)
			)
		)
		(property "License" "Apache-2.0"
			(at 0 0 270)
			(unlocked yes)
			(layer "B.Fab")
			(hide yes)
			(effects
				(font
					(size 1 1)
					(thickness 0.15)
				)
				(justify mirror)
			)
		)
		(property "Author" "Antmicro"
			(at 0 0 270)
			(unlocked yes)
			(layer "B.Fab")
			(hide yes)
			(effects
				(font
					(size 1 1)
					(thickness 0.15)
				)
				(justify mirror)
			)
		)
		(property "Val" "240R"
			(at 0 0 270)
			(unlocked yes)
			(layer "B.Fab")
			(hide yes)
			(effects
				(font
					(size 1 1)
					(thickness 0.15)
				)
				(justify mirror)
			)
		)
		(property "Tolerance" "1%"
			(at 0 0 270)
			(unlocked yes)
			(layer "B.Fab")
			(hide yes)
			(effects
				(font
					(size 1 1)
					(thickness 0.15)
				)
				(justify mirror)
			)
		)
		(sheetname "/FPGA banks HP/")
		(sheetfile "fpga-hp-banks.kicad_sch")
		(attr smd)
		(fp_rect
			(start -0.95 0.45)
			(end 0.95 -0.45)
			(stroke
				(width 0.05)
				(type default)
			)
			(fill no)
			(layer "B.CrtYd")
		)
		(fp_line
			(start -0.5 0.25)
			(end 0.499 0.25)
			(stroke
				(width 0.15)
				(type solid)
			)
			(layer "B.Fab")
		)
		(fp_line
			(start 0.499 0.25)
			(end 0.499 -0.249)
			(stroke
				(width 0.15)
				(type solid)
			)
			(layer "B.Fab")
		)
		(fp_line
			(start -0.5 -0.249)
			(end -0.5 0.25)
			(stroke
				(width 0.15)
				(type solid)
			)
			(layer "B.Fab")
		)
		(fp_line
			(start 0.499 -0.249)
			(end -0.5 -0.249)
			(stroke
				(width 0.15)
				(type solid)
			)
			(layer "B.Fab")
		)
		(fp_text user "${REFERENCE}"
			(at -0.95 -3.169 90)
			(layer "B.Fab")
			(effects
				(font
					(size 0.7 0.7)
					(thickness 0.15)
				)
				(justify left bottom mirror)
			)
		)
		(fp_text user "License: Apache-2.0"
			(at -0.95 -4.369 90)
			(layer "B.Fab")
			(effects
				(font
					(size 0.7 0.7)
					(thickness 0.15)
				)
				(justify left bottom mirror)
			)
		)
		(fp_text user "Author: Antmicro"
			(at -0.95 -5.569 90)
			(layer "B.Fab")
			(effects
				(font
					(size 0.7 0.7)
					(thickness 0.15)
				)
				(justify left bottom mirror)
			)
		)
		(pad "1" smd roundrect
			(at -0.5 0 180)
			(size 0.6 0.6)
			(layers "B.Cu" "B.Mask" "B.Paste")
			(roundrect_rratio 0.25)
			(net 601 "/FPGA banks HP/VRP_67")
			(pintype "passive")
		)
		(pad "2" smd roundrect
			(at 0.499 0 270)
			(size 0.6 0.6)
			(layers "B.Cu" "B.Mask" "B.Paste")
			(roundrect_rratio 0.25)
			(net 1 "GND")
			(pintype "passive")
		)
	)
)
